(kicad_pcb
	(version 20260206)
	(generator "pcbnew")
	(generator_version "10.0")
	(general
		(thickness 1.6)
		(legacy_teardrops no)
	)
	(paper "A4")
	(title_block
		(title "12092022_DA0F0TFB6D0_F0T_FAN_BOARD_MP5048_D_brd_v02_OCP.brd")
		(comment 1 "Grand Teton / footprints 56-61 of 924")
	)
	(layers
		(0 "F.Cu" signal "TOP")
		(4 "In1.Cu" signal "GND")
		(6 "In2.Cu" signal "IN1")
		(8 "In3.Cu" signal "IN2")
		(10 "In4.Cu" signal "GND1")
		(2 "B.Cu" signal "BOTTOM")
		(9 "F.Adhes" user "F.Adhesive")
		(11 "B.Adhes" user "B.Adhesive")
		(13 "F.Paste" user "Package Geometry/Pastemask Top")
		(15 "B.Paste" user "Package Geometry/Pastemask Bottom")
		(5 "F.SilkS" user "Ref Des/Silkscreen Top")
		(7 "B.SilkS" user "Ref Des/Silkscreen Bottom")
		(1 "F.Mask" user "Board Geometry/Soldermask Top")
		(3 "B.Mask" user "Board Geometry/Soldermask Bottom")
		(17 "Dwgs.User" user "User.Drawings")
		(19 "Cmts.User" user "User.Comments")
		(21 "Eco1.User" user "User.Eco1")
		(23 "Eco2.User" user "User.Eco2")
		(25 "Edge.Cuts" user "Board Geometry/Outline")
		(27 "Margin" user)
		(31 "F.CrtYd" user "Package Geometry/Place Bound Top")
		(29 "B.CrtYd" user "Package Geometry/Place Bound Bottom")
		(35 "F.Fab" user "Ref Des/Assembly Top")
		(33 "B.Fab" user "Ref Des/Assembly Bottom")
	)
	(footprint ""
		(layer "F.Cu")
		(at 4.191 -169.291 180)
		(property "Reference" "R4855"
			(at 0 0 180)
			(layer "F.SilkS")
			(hide yes)
			(effects
				(font
					(size 1.27 1.27)
				)
			)
		)
		(property "Value" ""
			(at 0 0 180)
			(layer "F.Fab")
			(effects
				(font
					(size 1.27 1.27)
				)
			)
		)
		(duplicate_pad_numbers_are_jumpers no)
		(fp_line
			(start 0.7874 0.4064)
			(end -0.7874 0.4064)
			(stroke
				(width 0.1524)
				(type default)
			)
			(layer "F.SilkS")
		)
		(fp_line
			(start 0.7874 -0.4064)
			(end 0.7874 0.4064)
			(stroke
				(width 0.1524)
				(type default)
			)
			(layer "F.SilkS")
		)
		(fp_line
			(start -0.7874 0.4064)
			(end -0.7874 -0.4064)
			(stroke
				(width 0.1524)
				(type default)
			)
			(layer "F.SilkS")
		)
		(fp_line
			(start -0.7874 -0.4064)
			(end 0.7874 -0.4064)
			(stroke
				(width 0.1524)
				(type default)
			)
			(layer "F.SilkS")
		)
		(fp_line
			(start 0.67945 0.3048)
			(end 0.120396 0.3048)
			(stroke
				(width 0.1)
				(type default)
			)
			(layer "F.Fab")
		)
		(fp_line
			(start 0.67945 -0.3048)
			(end 0.67945 0.3048)
			(stroke
				(width 0.1)
				(type default)
			)
			(layer "F.Fab")
		)
		(fp_line
			(start 0.12065 -0.2794)
			(end 0.12065 -0.3048)
			(stroke
				(width 0.1)
				(type default)
			)
			(layer "F.Fab")
		)
		(fp_line
			(start 0.12065 -0.3048)
			(end 0.67945 -0.3048)
			(stroke
				(width 0.1)
				(type default)
			)
			(layer "F.Fab")
		)
		(fp_line
			(start 0.120396 0.3048)
			(end 0.120396 0.2794)
			(stroke
				(width 0.1)
				(type default)
			)
			(layer "F.Fab")
		)
		(fp_line
			(start 0.120396 0.2794)
			(end -0.12065 0.2794)
			(stroke
				(width 0.1)
				(type default)
			)
			(layer "F.Fab")
		)
		(fp_line
			(start -0.12065 0.3048)
			(end -0.67945 0.3048)
			(stroke
				(width 0.1)
				(type default)
			)
			(layer "F.Fab")
		)
		(fp_line
			(start -0.12065 0.2794)
			(end -0.12065 0.3048)
			(stroke
				(width 0.1)
				(type default)
			)
			(layer "F.Fab")
		)
		(fp_line
			(start -0.12065 -0.2794)
			(end 0.12065 -0.2794)
			(stroke
				(width 0.1)
				(type default)
			)
			(layer "F.Fab")
		)
		(fp_line
			(start -0.12065 -0.305054)
			(end -0.12065 -0.2794)
			(stroke
				(width 0.1)
				(type default)
			)
			(layer "F.Fab")
		)
		(fp_line
			(start -0.67945 0.3048)
			(end -0.67945 -0.305054)
			(stroke
				(width 0.1)
				(type default)
			)
			(layer "F.Fab")
		)
		(fp_line
			(start -0.67945 -0.305054)
			(end -0.12065 -0.305054)
			(stroke
				(width 0.1)
				(type default)
			)
			(layer "F.Fab")
		)
		(pad "1" smd circle
			(at -0.40005 0 180)
			(size 0 0)
			(layers "F.Cu" "F.Mask" "F.Paste")
			(net "FAN_4_PRSNT_BUF_R_N")
		)
		(pad "2" smd circle
			(at 0.40005 0 180)
			(size 0 0)
			(layers "F.Cu" "F.Mask" "F.Paste")
			(net "FAN_4_PRSNT_BUF_N")
		)
	)
	(footprint ""
		(layer "F.Cu")
		(at 28.956 -162.941 90)
		(property "Reference" "R5270"
			(at 0 0 90)
			(layer "F.SilkS")
			(hide yes)
			(effects
				(font
					(size 1.27 1.27)
				)
			)
		)
		(property "Value" ""
			(at 0 0 90)
			(layer "F.Fab")
			(effects
				(font
					(size 1.27 1.27)
				)
			)
		)
		(duplicate_pad_numbers_are_jumpers no)
		(fp_line
			(start 0.7874 -0.4064)
			(end 0.7874 0.4064)
			(stroke
				(width 0.1524)
				(type default)
			)
			(layer "F.SilkS")
		)
		(fp_line
			(start -0.7874 -0.4064)
			(end 0.7874 -0.4064)
			(stroke
				(width 0.1524)
				(type default)
			)
			(layer "F.SilkS")
		)
		(fp_line
			(start 0.7874 0.4064)
			(end -0.7874 0.4064)
			(stroke
				(width 0.1524)
				(type default)
			)
			(layer "F.SilkS")
		)
		(fp_line
			(start -0.7874 0.4064)
			(end -0.7874 -0.4064)
			(stroke
				(width 0.1524)
				(type default)
			)
			(layer "F.SilkS")
		)
		(fp_line
			(start -0.12065 -0.305054)
			(end -0.12065 -0.2794)
			(stroke
				(width 0.1)
				(type default)
			)
			(layer "F.Fab")
		)
		(fp_line
			(start -0.67945 -0.305054)
			(end -0.12065 -0.305054)
			(stroke
				(width 0.1)
				(type default)
			)
			(layer "F.Fab")
		)
		(fp_line
			(start 0.67945 -0.3048)
			(end 0.67945 0.3048)
			(stroke
				(width 0.1)
				(type default)
			)
			(layer "F.Fab")
		)
		(fp_line
			(start 0.12065 -0.3048)
			(end 0.67945 -0.3048)
			(stroke
				(width 0.1)
				(type default)
			)
			(layer "F.Fab")
		)
		(fp_line
			(start 0.12065 -0.2794)
			(end 0.12065 -0.3048)
			(stroke
				(width 0.1)
				(type default)
			)
			(layer "F.Fab")
		)
		(fp_line
			(start -0.12065 -0.2794)
			(end 0.12065 -0.2794)
			(stroke
				(width 0.1)
				(type default)
			)
			(layer "F.Fab")
		)
		(fp_line
			(start 0.120396 0.2794)
			(end -0.12065 0.2794)
			(stroke
				(width 0.1)
				(type default)
			)
			(layer "F.Fab")
		)
		(fp_line
			(start -0.12065 0.2794)
			(end -0.12065 0.3048)
			(stroke
				(width 0.1)
				(type default)
			)
			(layer "F.Fab")
		)
		(fp_line
			(start 0.67945 0.3048)
			(end 0.120396 0.3048)
			(stroke
				(width 0.1)
				(type default)
			)
			(layer "F.Fab")
		)
		(fp_line
			(start 0.120396 0.3048)
			(end 0.120396 0.2794)
			(stroke
				(width 0.1)
				(type default)
			)
			(layer "F.Fab")
		)
		(fp_line
			(start -0.12065 0.3048)
			(end -0.67945 0.3048)
			(stroke
				(width 0.1)
				(type default)
			)
			(layer "F.Fab")
		)
		(fp_line
			(start -0.67945 0.3048)
			(end -0.67945 -0.305054)
			(stroke
				(width 0.1)
				(type default)
			)
			(layer "F.Fab")
		)
		(pad "1" smd circle
			(at -0.40005 0 90)
			(size 0 0)
			(layers "F.Cu" "F.Mask" "F.Paste")
			(net "SMB_FAN5_R_SCL")
		)
		(pad "2" smd circle
			(at 0.40005 0 90)
			(size 0 0)
			(layers "F.Cu" "F.Mask" "F.Paste")
			(net "P3V3_AUX")
		)
	)
	(footprint ""
		(layer "F.Cu")
		(at 4.191 -166.116 180)
		(property "Reference" "R104"
			(at 0 0 180)
			(layer "F.SilkS")
			(hide yes)
			(effects
				(font
					(size 1.27 1.27)
				)
			)
		)
		(property "Value" ""
			(at 0 0 180)
			(layer "F.Fab")
			(effects
				(font
					(size 1.27 1.27)
				)
			)
		)
		(duplicate_pad_numbers_are_jumpers no)
		(fp_line
			(start 0.7874 0.4064)
			(end -0.7874 0.4064)
			(stroke
				(width 0.1524)
				(type default)
			)
			(layer "F.SilkS")
		)
		(fp_line
			(start 0.7874 -0.4064)
			(end 0.7874 0.4064)
			(stroke
				(width 0.1524)
				(type default)
			)
			(layer "F.SilkS")
		)
		(fp_line
			(start -0.7874 0.4064)
			(end -0.7874 -0.4064)
			(stroke
				(width 0.1524)
				(type default)
			)
			(layer "F.SilkS")
		)
		(fp_line
			(start -0.7874 -0.4064)
			(end 0.7874 -0.4064)
			(stroke
				(width 0.1524)
				(type default)
			)
			(layer "F.SilkS")
		)
		(fp_line
			(start 0.67945 0.3048)
			(end 0.120396 0.3048)
			(stroke
				(width 0.1)
				(type default)
			)
			(layer "F.Fab")
		)
		(fp_line
			(start 0.67945 -0.3048)
			(end 0.67945 0.3048)
			(stroke
				(width 0.1)
				(type default)
			)
			(layer "F.Fab")
		)
		(fp_line
			(start 0.12065 -0.2794)
			(end 0.12065 -0.3048)
			(stroke
				(width 0.1)
				(type default)
			)
			(layer "F.Fab")
		)
		(fp_line
			(start 0.12065 -0.3048)
			(end 0.67945 -0.3048)
			(stroke
				(width 0.1)
				(type default)
			)
			(layer "F.Fab")
		)
		(fp_line
			(start 0.120396 0.3048)
			(end 0.120396 0.2794)
			(stroke
				(width 0.1)
				(type default)
			)
			(layer "F.Fab")
		)
		(fp_line
			(start 0.120396 0.2794)
			(end -0.12065 0.2794)
			(stroke
				(width 0.1)
				(type default)
			)
			(layer "F.Fab")
		)
		(fp_line
			(start -0.12065 0.3048)
			(end -0.67945 0.3048)
			(stroke
				(width 0.1)
				(type default)
			)
			(layer "F.Fab")
		)
		(fp_line
			(start -0.12065 0.2794)
			(end -0.12065 0.3048)
			(stroke
				(width 0.1)
				(type default)
			)
			(layer "F.Fab")
		)
		(fp_line
			(start -0.12065 -0.2794)
			(end 0.12065 -0.2794)
			(stroke
				(width 0.1)
				(type default)
			)
			(layer "F.Fab")
		)
		(fp_line
			(start -0.12065 -0.305054)
			(end -0.12065 -0.2794)
			(stroke
				(width 0.1)
				(type default)
			)
			(layer "F.Fab")
		)
		(fp_line
			(start -0.67945 0.3048)
			(end -0.67945 -0.305054)
			(stroke
				(width 0.1)
				(type default)
			)
			(layer "F.Fab")
		)
		(fp_line
			(start -0.67945 -0.305054)
			(end -0.12065 -0.305054)
			(stroke
				(width 0.1)
				(type default)
			)
			(layer "F.Fab")
		)
		(pad "1" smd circle
			(at -0.40005 0 180)
			(size 0 0)
			(layers "F.Cu" "F.Mask" "F.Paste")
			(net "FAN_2_PRSNT_BUF_R_N")
		)
		(pad "2" smd circle
			(at 0.40005 0 180)
			(size 0 0)
			(layers "F.Cu" "F.Mask" "F.Paste")
			(net "FAN_2_PRSNT_BUF_N")
		)
	)
	(footprint ""
		(layer "F.Cu")
		(at 4.191 -172.847 180)
		(property "Reference" "R4863"
			(at 0 0 180)
			(layer "F.SilkS")
			(hide yes)
			(effects
				(font
					(size 1.27 1.27)
				)
			)
		)
		(property "Value" ""
			(at 0 0 180)
			(layer "F.Fab")
			(effects
				(font
					(size 1.27 1.27)
				)
			)
		)
		(duplicate_pad_numbers_are_jumpers no)
		(fp_line
			(start 0.7874 0.4064)
			(end -0.7874 0.4064)
			(stroke
				(width 0.1524)
				(type default)
			)
			(layer "F.SilkS")
		)
		(fp_line
			(start 0.7874 -0.4064)
			(end 0.7874 0.4064)
			(stroke
				(width 0.1524)
				(type default)
			)
			(layer "F.SilkS")
		)
		(fp_line
			(start -0.7874 0.4064)
			(end -0.7874 -0.4064)
			(stroke
				(width 0.1524)
				(type default)
			)
			(layer "F.SilkS")
		)
		(fp_line
			(start -0.7874 -0.4064)
			(end 0.7874 -0.4064)
			(stroke
				(width 0.1524)
				(type default)
			)
			(layer "F.SilkS")
		)
		(fp_line
			(start 0.67945 0.3048)
			(end 0.120396 0.3048)
			(stroke
				(width 0.1)
				(type default)
			)
			(layer "F.Fab")
		)
		(fp_line
			(start 0.67945 -0.3048)
			(end 0.67945 0.3048)
			(stroke
				(width 0.1)
				(type default)
			)
			(layer "F.Fab")
		)
		(fp_line
			(start 0.12065 -0.2794)
			(end 0.12065 -0.3048)
			(stroke
				(width 0.1)
				(type default)
			)
			(layer "F.Fab")
		)
		(fp_line
			(start 0.12065 -0.3048)
			(end 0.67945 -0.3048)
			(stroke
				(width 0.1)
				(type default)
			)
			(layer "F.Fab")
		)
		(fp_line
			(start 0.120396 0.3048)
			(end 0.120396 0.2794)
			(stroke
				(width 0.1)
				(type default)
			)
			(layer "F.Fab")
		)
		(fp_line
			(start 0.120396 0.2794)
			(end -0.12065 0.2794)
			(stroke
				(width 0.1)
				(type default)
			)
			(layer "F.Fab")
		)
		(fp_line
			(start -0.12065 0.3048)
			(end -0.67945 0.3048)
			(stroke
				(width 0.1)
				(type default)
			)
			(layer "F.Fab")
		)
		(fp_line
			(start -0.12065 0.2794)
			(end -0.12065 0.3048)
			(stroke
				(width 0.1)
				(type default)
			)
			(layer "F.Fab")
		)
		(fp_line
			(start -0.12065 -0.2794)
			(end 0.12065 -0.2794)
			(stroke
				(width 0.1)
				(type default)
			)
			(layer "F.Fab")
		)
		(fp_line
			(start -0.12065 -0.305054)
			(end -0.12065 -0.2794)
			(stroke
				(width 0.1)
				(type default)
			)
			(layer "F.Fab")
		)
		(fp_line
			(start -0.67945 0.3048)
			(end -0.67945 -0.305054)
			(stroke
				(width 0.1)
				(type default)
			)
			(layer "F.Fab")
		)
		(fp_line
			(start -0.67945 -0.305054)
			(end -0.12065 -0.305054)
			(stroke
				(width 0.1)
				(type default)
			)
			(layer "F.Fab")
		)
		(pad "1" smd circle
			(at -0.40005 0 180)
			(size 0 0)
			(layers "F.Cu" "F.Mask" "F.Paste")
			(net "FAN_6_PRSNT_BUF_R_N")
		)
		(pad "2" smd circle
			(at 0.40005 0 180)
			(size 0 0)
			(layers "F.Cu" "F.Mask" "F.Paste")
			(net "FAN_6_PRSNT_BUF_N")
		)
	)
	(footprint ""
		(layer "F.Cu")
		(at 33.02 -193.548 180)
		(property "Reference" "R5307"
			(at 0 0 180)
			(layer "F.SilkS")
			(hide yes)
			(effects
				(font
					(size 1.27 1.27)
				)
			)
		)
		(property "Value" ""
			(at 0 0 180)
			(layer "F.Fab")
			(effects
				(font
					(size 1.27 1.27)
				)
			)
		)
		(duplicate_pad_numbers_are_jumpers no)
		(fp_line
			(start 0.7874 0.4064)
			(end -0.7874 0.4064)
			(stroke
				(width 0.1524)
				(type default)
			)
			(layer "F.SilkS")
		)
		(fp_line
			(start 0.7874 -0.4064)
			(end 0.7874 0.4064)
			(stroke
				(width 0.1524)
				(type default)
			)
			(layer "F.SilkS")
		)
		(fp_line
			(start -0.7874 0.4064)
			(end -0.7874 -0.4064)
			(stroke
				(width 0.1524)
				(type default)
			)
			(layer "F.SilkS")
		)
		(fp_line
			(start -0.7874 -0.4064)
			(end 0.7874 -0.4064)
			(stroke
				(width 0.1524)
				(type default)
			)
			(layer "F.SilkS")
		)
		(fp_line
			(start 0.67945 0.3048)
			(end 0.120396 0.3048)
			(stroke
				(width 0.1)
				(type default)
			)
			(layer "F.Fab")
		)
		(fp_line
			(start 0.67945 -0.3048)
			(end 0.67945 0.3048)
			(stroke
				(width 0.1)
				(type default)
			)
			(layer "F.Fab")
		)
		(fp_line
			(start 0.12065 -0.2794)
			(end 0.12065 -0.3048)
			(stroke
				(width 0.1)
				(type default)
			)
			(layer "F.Fab")
		)
		(fp_line
			(start 0.12065 -0.3048)
			(end 0.67945 -0.3048)
			(stroke
				(width 0.1)
				(type default)
			)
			(layer "F.Fab")
		)
		(fp_line
			(start 0.120396 0.3048)
			(end 0.120396 0.2794)
			(stroke
				(width 0.1)
				(type default)
			)
			(layer "F.Fab")
		)
		(fp_line
			(start 0.120396 0.2794)
			(end -0.12065 0.2794)
			(stroke
				(width 0.1)
				(type default)
			)
			(layer "F.Fab")
		)
		(fp_line
			(start -0.12065 0.3048)
			(end -0.67945 0.3048)
			(stroke
				(width 0.1)
				(type default)
			)
			(layer "F.Fab")
		)
		(fp_line
			(start -0.12065 0.2794)
			(end -0.12065 0.3048)
			(stroke
				(width 0.1)
				(type default)
			)
			(layer "F.Fab")
		)
		(fp_line
			(start -0.12065 -0.2794)
			(end 0.12065 -0.2794)
			(stroke
				(width 0.1)
				(type default)
			)
			(layer "F.Fab")
		)
		(fp_line
			(start -0.12065 -0.305054)
			(end -0.12065 -0.2794)
			(stroke
				(width 0.1)
				(type default)
			)
			(layer "F.Fab")
		)
		(fp_line
			(start -0.67945 0.3048)
			(end -0.67945 -0.305054)
			(stroke
				(width 0.1)
				(type default)
			)
			(layer "F.Fab")
		)
		(fp_line
			(start -0.67945 -0.305054)
			(end -0.12065 -0.305054)
			(stroke
				(width 0.1)
				(type default)
			)
			(layer "F.Fab")
		)
		(pad "1" smd rect
			(at -0.40005 0)
			(size 0.4572 0.508)
			(layers "F.Cu" "F.Mask" "F.Paste")
			(net "FAN_1_TACH_OL_R")
		)
		(pad "2" smd rect
			(at 0.40005 0)
			(size 0.4572 0.508)
			(layers "F.Cu" "F.Mask" "F.Paste")
			(net "FAN_1_TACH_OL")
		)
	)
	(footprint ""
		(layer "F.Cu")
		(at 14.234922 -194.250056 180)
		(property "Reference" "R5218"
			(at 0 0 180)
			(layer "F.SilkS")
			(hide yes)
			(effects
				(font
					(size 1.27 1.27)
				)
			)
		)
		(property "Value" ""
			(at 0 0 180)
			(layer "F.Fab")
			(effects
				(font
					(size 1.27 1.27)
				)
			)
		)
		(duplicate_pad_numbers_are_jumpers no)
		(fp_line
			(start 0.7874 0.4064)
			(end -0.7874 0.4064)
			(stroke
				(width 0.1524)
				(type default)
			)
			(layer "F.SilkS")
		)
		(fp_line
			(start 0.7874 -0.4064)
			(end 0.7874 0.4064)
			(stroke
				(width 0.1524)
				(type default)
			)
			(layer "F.SilkS")
		)
		(fp_line
			(start -0.7874 0.4064)
			(end -0.7874 -0.4064)
			(stroke
				(width 0.1524)
				(type default)
			)
			(layer "F.SilkS")
		)
		(fp_line
			(start -0.7874 -0.4064)
			(end 0.7874 -0.4064)
			(stroke
				(width 0.1524)
				(type default)
			)
			(layer "F.SilkS")
		)
		(fp_line
			(start 0.67945 0.3048)
			(end 0.120396 0.3048)
			(stroke
				(width 0.1)
				(type default)
			)
			(layer "F.Fab")
		)
		(fp_line
			(start 0.67945 -0.3048)
			(end 0.67945 0.3048)
			(stroke
				(width 0.1)
				(type default)
			)
			(layer "F.Fab")
		)
		(fp_line
			(start 0.12065 -0.2794)
			(end 0.12065 -0.3048)
			(stroke
				(width 0.1)
				(type default)
			)
			(layer "F.Fab")
		)
		(fp_line
			(start 0.12065 -0.3048)
			(end 0.67945 -0.3048)
			(stroke
				(width 0.1)
				(type default)
			)
			(layer "F.Fab")
		)
		(fp_line
			(start 0.120396 0.3048)
			(end 0.120396 0.2794)
			(stroke
				(width 0.1)
				(type default)
			)
			(layer "F.Fab")
		)
		(fp_line
			(start 0.120396 0.2794)
			(end -0.12065 0.2794)
			(stroke
				(width 0.1)
				(type default)
			)
			(layer "F.Fab")
		)
		(fp_line
			(start -0.12065 0.3048)
			(end -0.67945 0.3048)
			(stroke
				(width 0.1)
				(type default)
			)
			(layer "F.Fab")
		)
		(fp_line
			(start -0.12065 0.2794)
			(end -0.12065 0.3048)
			(stroke
				(width 0.1)
				(type default)
			)
			(layer "F.Fab")
		)
		(fp_line
			(start -0.12065 -0.2794)
			(end 0.12065 -0.2794)
			(stroke
				(width 0.1)
				(type default)
			)
			(layer "F.Fab")
		)
		(fp_line
			(start -0.12065 -0.305054)
			(end -0.12065 -0.2794)
			(stroke
				(width 0.1)
				(type default)
			)
			(layer "F.Fab")
		)
		(fp_line
			(start -0.67945 0.3048)
			(end -0.67945 -0.305054)
			(stroke
				(width 0.1)
				(type default)
			)
			(layer "F.Fab")
		)
		(fp_line
			(start -0.67945 -0.305054)
			(end -0.12065 -0.305054)
			(stroke
				(width 0.1)
				(type default)
			)
			(layer "F.Fab")
		)
		(pad "1" smd circle
			(at -0.40005 0 180)
			(size 0 0)
			(layers "F.Cu" "F.Mask" "F.Paste")
			(net "FAN_6_PWM_OL")
		)
		(pad "2" smd circle
			(at 0.40005 0 180)
			(size 0 0)
			(layers "F.Cu" "F.Mask" "F.Paste")
			(net "FAN_6_PWM_OL_R")
		)
	)
)
